(kicad_pcb
	(version 20241229)
	(generator "pcbnew")
	(generator_version "9.0")
	(general
		(thickness 1.294)
		(legacy_teardrops no)
	)
	(paper "A3")
	(title_block
		(title "Kintex 410T devboard")
		(date "2024-04-03")
		(rev "1.1.2")
		(comment 9 "footprints 314-319 of 975")
	)
	(layers
		(0 "F.Cu" mixed)
		(4 "In1.Cu" power)
		(6 "In2.Cu" power)
		(8 "In3.Cu" mixed)
		(10 "In4.Cu" power)
		(12 "In5.Cu" mixed)
		(14 "In6.Cu" power)
		(16 "In7.Cu" mixed)
		(18 "In8.Cu" power)
		(2 "B.Cu" mixed)
		(9 "F.Adhes" user "F.Adhesive")
		(11 "B.Adhes" user "B.Adhesive")
		(13 "F.Paste" user)
		(15 "B.Paste" user)
		(5 "F.SilkS" user "F.Silkscreen")
		(7 "B.SilkS" user "B.Silkscreen")
		(1 "F.Mask" user)
		(3 "B.Mask" user)
		(17 "Dwgs.User" user "User.Drawings")
		(19 "Cmts.User" user "User.Comments")
		(21 "Eco1.User" user "User.Eco1")
		(23 "Eco2.User" user "User.Eco2")
		(25 "Edge.Cuts" user)
		(27 "Margin" user)
		(31 "F.CrtYd" user "F.Courtyard")
		(29 "B.CrtYd" user "B.Courtyard")
		(35 "F.Fab" user)
		(33 "B.Fab" user)
	)
	(footprint "antmicro-footprints:FB_0603_1608Metric"
		(layer "F.Cu")
		(at 256.845 135.035 180)
		(property "Reference" "FB6"
			(at 0.795 4.085 180)
			(layer "F.SilkS")
			(effects
				(font
					(size 0.7 0.7)
					(thickness 0.15)
				)
				(justify left bottom)
			)
		)
		(property "Value" "FB_600Z_0.5A_Murata-BLM18AG_0603"
			(at 0 1.7 180)
			(layer "F.Fab")
			(effects
				(font
					(size 0.7 0.7)
					(thickness 0.15)
				)
				(justify left bottom)
			)
		)
		(property "Description" "Ferrite Bead, 0603 [1608 Metric], 600 ohm, 500 mA, BLM18A, 0.38 ohm, ± 25%, General use"
			(at 0 0 180)
			(layer "F.Fab")
			(hide yes)
			(effects
				(font
					(size 1.27 1.27)
					(thickness 0.15)
				)
			)
		)
		(property "Author" "Antmicro"
			(at 513.69 270.07 0)
			(layer "F.Fab")
			(hide yes)
			(effects
				(font
					(size 1 1)
					(thickness 0.15)
				)
			)
		)
		(property "Current" ""
			(at 513.69 270.07 0)
			(layer "F.Fab")
			(hide yes)
			(effects
				(font
					(size 1 1)
					(thickness 0.15)
				)
			)
		)
		(property "License" "Apache-2.0"
			(at 513.69 270.07 0)
			(layer "F.Fab")
			(hide yes)
			(effects
				(font
					(size 1 1)
					(thickness 0.15)
				)
			)
		)
		(property "MPN" "BLM18AG601SN1D"
			(at 513.69 270.07 0)
			(layer "F.Fab")
			(hide yes)
			(effects
				(font
					(size 1 1)
					(thickness 0.15)
				)
			)
		)
		(property "Manufacturer" "Murata"
			(at 513.69 270.07 0)
			(layer "F.Fab")
			(hide yes)
			(effects
				(font
					(size 1 1)
					(thickness 0.15)
				)
			)
		)
		(property "Val" "600Z/0.5A"
			(at 513.69 270.07 0)
			(layer "F.Fab")
			(hide yes)
			(effects
				(font
					(size 1 1)
					(thickness 0.15)
				)
			)
		)
		(sheetname "USB PHY")
		(sheetfile "usb-phy.kicad_sch")
		(attr smd)
		(fp_line
			(start -0.15 0.4)
			(end 0.15 0.4)
			(stroke
				(width 0.15)
				(type solid)
			)
			(layer "F.SilkS")
		)
		(fp_line
			(start -0.15 -0.4)
			(end 0.15 -0.4)
			(stroke
				(width 0.15)
				(type solid)
			)
			(layer "F.SilkS")
		)
		(fp_rect
			(start -1.25 -0.65)
			(end 1.25 0.65)
			(stroke
				(width 0.05)
				(type solid)
			)
			(fill no)
			(layer "F.CrtYd")
		)
		(fp_line
			(start 0.8 0.406)
			(end -0.803 0.406)
			(stroke
				(width 0.15)
				(type solid)
			)
			(layer "F.Fab")
		)
		(fp_line
			(start 0.8 -0.408)
			(end 0.8 0.406)
			(stroke
				(width 0.15)
				(type solid)
			)
			(layer "F.Fab")
		)
		(fp_line
			(start 0.8 -0.408)
			(end -0.803 -0.408)
			(stroke
				(width 0.15)
				(type solid)
			)
			(layer "F.Fab")
		)
		(fp_line
			(start -0.803 0.406)
			(end -0.803 -0.408)
			(stroke
				(width 0.15)
				(type solid)
			)
			(layer "F.Fab")
		)
		(pad "1" smd roundrect
			(at -0.7 0 180)
			(size 0.8 1)
			(layers "F.Cu" "F.Mask" "F.Paste")
			(roundrect_rratio 0.2)
			(net 707 "/USB PHY/FTDI_3V3")
			(pintype "passive")
		)
		(pad "2" smd roundrect
			(at 0.7 0 180)
			(size 0.8 1)
			(layers "F.Cu" "F.Mask" "F.Paste")
			(roundrect_rratio 0.2)
			(net 711 "/USB PHY/FTDI_VPLL")
			(pintype "passive")
		)
	)
	(footprint "antmicro-footprints:C_0603_1608Metric"
		(layer "F.Cu")
		(at 157.95 164.05 180)
		(descr "Capacitor SMD 0603")
		(tags "capacitor 0603")
		(property "Reference" "C326"
			(at 1 -0.4 0)
			(layer "F.SilkS")
			(effects
				(font
					(size 0.7 0.7)
					(thickness 0.15)
				)
				(justify right bottom)
			)
		)
		(property "Value" "C_22u_0603"
			(at 0 1.6 0)
			(layer "F.Fab")
			(effects
				(font
					(size 0.7 0.7)
					(thickness 0.15)
				)
				(justify right bottom)
			)
		)
		(property "Description" "SMD Multilayer Ceramic Capacitor, 22 µF, 6.3 V, 0603 [1608 Metric], ± 20%, X5R, GRM Series"
			(at 0 0 180)
			(layer "F.Fab")
			(hide yes)
			(effects
				(font
					(size 1.27 1.27)
					(thickness 0.15)
				)
			)
		)
		(property "Author" "Antmicro"
			(at 315.9 328.1 0)
			(layer "F.Fab")
			(hide yes)
			(effects
				(font
					(size 1 1)
					(thickness 0.15)
				)
			)
		)
		(property "Dielectric" ""
			(at 315.9 328.1 0)
			(layer "F.Fab")
			(hide yes)
			(effects
				(font
					(size 1 1)
					(thickness 0.15)
				)
			)
		)
		(property "License" "Apache-2.0"
			(at 315.9 328.1 0)
			(layer "F.Fab")
			(hide yes)
			(effects
				(font
					(size 1 1)
					(thickness 0.15)
				)
			)
		)
		(property "MPN" "GRM188R60J226MEA0D"
			(at 315.9 328.1 0)
			(layer "F.Fab")
			(hide yes)
			(effects
				(font
					(size 1 1)
					(thickness 0.15)
				)
			)
		)
		(property "Manufacturer" "Murata"
			(at 315.9 328.1 0)
			(layer "F.Fab")
			(hide yes)
			(effects
				(font
					(size 1 1)
					(thickness 0.15)
				)
			)
		)
		(property "Val" "22u"
			(at 315.9 328.1 0)
			(layer "F.Fab")
			(hide yes)
			(effects
				(font
					(size 1 1)
					(thickness 0.15)
				)
			)
		)
		(property "Voltage" ""
			(at 315.9 328.1 0)
			(layer "F.Fab")
			(hide yes)
			(effects
				(font
					(size 1 1)
					(thickness 0.15)
				)
			)
		)
		(sheetname "DC-DC Converters")
		(sheetfile "dc-dc.kicad_sch")
		(attr smd)
		(fp_line
			(start -0.15 0.4)
			(end 0.15 0.4)
			(stroke
				(width 0.15)
				(type solid)
			)
			(layer "F.SilkS")
		)
		(fp_line
			(start -0.15 -0.4)
			(end 0.15 -0.4)
			(stroke
				(width 0.15)
				(type solid)
			)
			(layer "F.SilkS")
		)
		(fp_rect
			(start -1.25 -0.65)
			(end 1.25 0.65)
			(stroke
				(width 0.05)
				(type solid)
			)
			(fill no)
			(layer "F.CrtYd")
		)
		(fp_rect
			(start -0.8 -0.4)
			(end 0.8 0.4)
			(stroke
				(width 0.15)
				(type solid)
			)
			(fill no)
			(layer "F.Fab")
		)
		(pad "1" smd roundrect
			(at -0.7 0 180)
			(size 0.8 1)
			(layers "F.Cu" "F.Mask" "F.Paste")
			(roundrect_rratio 0.2)
			(net 1 "GND")
			(pintype "passive")
		)
		(pad "2" smd roundrect
			(at 0.7 0 180)
			(size 0.8 1)
			(layers "F.Cu" "F.Mask" "F.Paste")
			(roundrect_rratio 0.2)
			(net 733 "/DC-DC Converters/MGTAVCC_local")
			(pintype "passive")
		)
	)
	(footprint "antmicro-footprints:C_0402_1005Metric"
		(layer "F.Cu")
		(at 156.2 144.665 -90)
		(descr "Capacitor SMD 0402")
		(tags "capacitor SMD 0402")
		(property "Reference" "C352"
			(at 1.085 0.5 90)
			(layer "F.SilkS")
			(effects
				(font
					(size 0.7 0.7)
					(thickness 0.15)
				)
				(justify right bottom)
			)
		)
		(property "Value" "C_1u_0402"
			(at 0 1.4 90)
			(layer "F.Fab")
			(effects
				(font
					(size 0.7 0.7)
					(thickness 0.15)
				)
				(justify right bottom)
			)
		)
		(property "Description" "SMD Multilayer Ceramic Capacitor, 1 µF, 10 V, 0402 [1005 Metric], ± 10%, X6S, C"
			(at 0 0 270)
			(layer "F.Fab")
			(hide yes)
			(effects
				(font
					(size 1.27 1.27)
					(thickness 0.15)
				)
			)
		)
		(property "Author" "Antmicro"
			(at 11.535 300.865 0)
			(layer "F.Fab")
			(hide yes)
			(effects
				(font
					(size 1 1)
					(thickness 0.15)
				)
			)
		)
		(property "Dielectric" ""
			(at 11.535 300.865 0)
			(layer "F.Fab")
			(hide yes)
			(effects
				(font
					(size 1 1)
					(thickness 0.15)
				)
			)
		)
		(property "License" "Apache-2.0"
			(at 11.535 300.865 0)
			(layer "F.Fab")
			(hide yes)
			(effects
				(font
					(size 1 1)
					(thickness 0.15)
				)
			)
		)
		(property "MPN" "C1005X6S1A105K050BC"
			(at 11.535 300.865 0)
			(layer "F.Fab")
			(hide yes)
			(effects
				(font
					(size 1 1)
					(thickness 0.15)
				)
			)
		)
		(property "Manufacturer" "TDK"
			(at 11.535 300.865 0)
			(layer "F.Fab")
			(hide yes)
			(effects
				(font
					(size 1 1)
					(thickness 0.15)
				)
			)
		)
		(property "Val" "1u"
			(at 11.535 300.865 0)
			(layer "F.Fab")
			(hide yes)
			(effects
				(font
					(size 1 1)
					(thickness 0.15)
				)
			)
		)
		(property "Voltage" ""
			(at 11.535 300.865 0)
			(layer "F.Fab")
			(hide yes)
			(effects
				(font
					(size 1 1)
					(thickness 0.15)
				)
			)
		)
		(sheetname "DC-DC Converters")
		(sheetfile "dc-dc.kicad_sch")
		(attr smd)
		(fp_rect
			(start -0.925 -0.47)
			(end 0.925 0.47)
			(stroke
				(width 0.05)
				(type default)
			)
			(fill no)
			(layer "F.CrtYd")
		)
		(fp_line
			(start -0.494 0.248)
			(end -0.494 -0.25)
			(stroke
				(width 0.15)
				(type solid)
			)
			(layer "F.Fab")
		)
		(fp_line
			(start 0.504 0.248)
			(end -0.494 0.248)
			(stroke
				(width 0.15)
				(type solid)
			)
			(layer "F.Fab")
		)
		(fp_line
			(start -0.494 -0.25)
			(end 0.504 -0.25)
			(stroke
				(width 0.15)
				(type solid)
			)
			(layer "F.Fab")
		)
		(fp_line
			(start 0.504 -0.25)
			(end 0.504 0.248)
			(stroke
				(width 0.15)
				(type solid)
			)
			(layer "F.Fab")
		)
		(pad "1" smd roundrect
			(at -0.48 0 270)
			(size 0.59 0.64)
			(layers "F.Cu" "F.Mask" "F.Paste")
			(roundrect_rratio 0.25)
			(net 1 "GND")
			(pintype "passive")
		)
		(pad "2" smd roundrect
			(at 0.48 0 270)
			(size 0.59 0.64)
			(layers "F.Cu" "F.Mask" "F.Paste")
			(roundrect_rratio 0.25)
			(net 747 "/DC-DC Converters/1V85_OUT")
			(pintype "passive")
		)
	)
	(footprint "antmicro-footprints:C_0402_1005Metric"
		(layer "F.Cu")
		(at 173.570001 108.063751 180)
		(descr "Capacitor SMD 0402")
		(tags "capacitor SMD 0402")
		(property "Reference" "C300"
			(at -3.729999 -0.383749 0)
			(layer "F.SilkS")
			(effects
				(font
					(size 0.7 0.7)
					(thickness 0.15)
				)
				(justify right bottom)
			)
		)
		(property "Value" "C_100n_0402"
			(at 0 1.4 0)
			(layer "F.Fab")
			(effects
				(font
					(size 0.7 0.7)
					(thickness 0.15)
				)
				(justify right bottom)
			)
		)
		(property "Description" "SMD Multilayer Ceramic Capacitor, 0.1 µF, 50 V, 0402 [1005 Metric], ± 10%, X5R, GRM Series"
			(at 0 0 180)
			(layer "F.Fab")
			(hide yes)
			(effects
				(font
					(size 1.27 1.27)
					(thickness 0.15)
				)
			)
		)
		(property "Author" "Antmicro"
			(at 347.140002 216.127502 0)
			(layer "F.Fab")
			(hide yes)
			(effects
				(font
					(size 1 1)
					(thickness 0.15)
				)
			)
		)
		(property "Dielectric" "X5R"
			(at 347.140002 216.127502 0)
			(layer "F.Fab")
			(hide yes)
			(effects
				(font
					(size 1 1)
					(thickness 0.15)
				)
			)
		)
		(property "License" "Apache-2.0"
			(at 347.140002 216.127502 0)
			(layer "F.Fab")
			(hide yes)
			(effects
				(font
					(size 1 1)
					(thickness 0.15)
				)
			)
		)
		(property "MPN" "GRM155R61H104KE14D"
			(at 347.140002 216.127502 0)
			(layer "F.Fab")
			(hide yes)
			(effects
				(font
					(size 1 1)
					(thickness 0.15)
				)
			)
		)
		(property "Manufacturer" "Murata"
			(at 347.140002 216.127502 0)
			(layer "F.Fab")
			(hide yes)
			(effects
				(font
					(size 1 1)
					(thickness 0.15)
				)
			)
		)
		(property "Val" "100n"
			(at 347.140002 216.127502 0)
			(layer "F.Fab")
			(hide yes)
			(effects
				(font
					(size 1 1)
					(thickness 0.15)
				)
			)
		)
		(property "Voltage" "50V"
			(at 347.140002 216.127502 0)
			(layer "F.Fab")
			(hide yes)
			(effects
				(font
					(size 1 1)
					(thickness 0.15)
				)
			)
		)
		(sheetname "FMC+ HSPC")
		(sheetfile "fmc-hspc.kicad_sch")
		(attr smd)
		(fp_rect
			(start -0.925 -0.47)
			(end 0.925 0.47)
			(stroke
				(width 0.05)
				(type default)
			)
			(fill no)
			(layer "F.CrtYd")
		)
		(fp_line
			(start 0.504 0.248)
			(end -0.494 0.248)
			(stroke
				(width 0.15)
				(type solid)
			)
			(layer "F.Fab")
		)
		(fp_line
			(start 0.504 -0.25)
			(end 0.504 0.248)
			(stroke
				(width 0.15)
				(type solid)
			)
			(layer "F.Fab")
		)
		(fp_line
			(start -0.494 0.248)
			(end -0.494 -0.25)
			(stroke
				(width 0.15)
				(type solid)
			)
			(layer "F.Fab")
		)
		(fp_line
			(start -0.494 -0.25)
			(end 0.504 -0.25)
			(stroke
				(width 0.15)
				(type solid)
			)
			(layer "F.Fab")
		)
		(pad "1" smd roundrect
			(at -0.48 0 180)
			(size 0.59 0.64)
			(layers "F.Cu" "F.Mask" "F.Paste")
			(roundrect_rratio 0.25)
			(net 65 "/FMC+ HSPC/GTX116.TX2_P")
			(pintype "passive")
		)
		(pad "2" smd roundrect
			(at 0.48 0 180)
			(size 0.59 0.64)
			(layers "F.Cu" "F.Mask" "F.Paste")
			(roundrect_rratio 0.25)
			(net 64 "/FMC+ HSPC/GTX_TX1_C_P")
			(pintype "passive")
		)
	)
	(footprint "antmicro-footprints:R_0402_1005Metric"
		(layer "F.Cu")
		(at 238.65 141.7 90)
		(descr "Resistor SMD 0402")
		(tags "resistor SMD 0402")
		(property "Reference" "R180"
			(at -3.85 4.9 90)
			(layer "F.SilkS")
			(effects
				(font
					(size 0.7 0.7)
					(thickness 0.15)
				)
				(justify left bottom)
			)
		)
		(property "Value" "R_0R_0402"
			(at 0 1.4 90)
			(layer "F.Fab")
			(effects
				(font
					(size 0.7 0.7)
					(thickness 0.15)
				)
				(justify left bottom)
			)
		)
		(property "Description" "SMD Chip Resistor, Jumper, 0 ohm, 100 mW, 0402 [1005 Metric], Thick Film, General Purpose"
			(at 0 0 90)
			(layer "F.Fab")
			(hide yes)
			(effects
				(font
					(size 1.27 1.27)
					(thickness 0.15)
				)
			)
		)
		(property "Author" "Antmicro"
			(at 380.35 -96.95 0)
			(layer "F.Fab")
			(hide yes)
			(effects
				(font
					(size 1 1)
					(thickness 0.15)
				)
			)
		)
		(property "Current" "1A"
			(at 380.35 -96.95 0)
			(layer "F.Fab")
			(hide yes)
			(effects
				(font
					(size 1 1)
					(thickness 0.15)
				)
			)
		)
		(property "License" "Apache-2.0"
			(at 380.35 -96.95 0)
			(layer "F.Fab")
			(hide yes)
			(effects
				(font
					(size 1 1)
					(thickness 0.15)
				)
			)
		)
		(property "MPN" "ERJ2GE0R00X"
			(at 380.35 -96.95 0)
			(layer "F.Fab")
			(hide yes)
			(effects
				(font
					(size 1 1)
					(thickness 0.15)
				)
			)
		)
		(property "Manufacturer" "Panasonic"
			(at 380.35 -96.95 0)
			(layer "F.Fab")
			(hide yes)
			(effects
				(font
					(size 1 1)
					(thickness 0.15)
				)
			)
		)
		(property "Tolerance" ""
			(at 380.35 -96.95 0)
			(layer "F.Fab")
			(hide yes)
			(effects
				(font
					(size 1 1)
					(thickness 0.15)
				)
			)
		)
		(property "Val" "0R"
			(at 380.35 -96.95 0)
			(layer "F.Fab")
			(hide yes)
			(effects
				(font
					(size 1 1)
					(thickness 0.15)
				)
			)
		)
		(sheetname "USB PHY")
		(sheetfile "usb-phy.kicad_sch")
		(attr smd)
		(fp_rect
			(start -0.925 -0.47)
			(end 0.925 0.47)
			(stroke
				(width 0.05)
				(type default)
			)
			(fill no)
			(layer "F.CrtYd")
		)
		(fp_rect
			(start -0.5 -0.25)
			(end 0.5 0.25)
			(stroke
				(width 0.15)
				(type solid)
			)
			(fill no)
			(layer "F.Fab")
		)
		(pad "1" smd roundrect
			(at -0.48 0 90)
			(size 0.59 0.64)
			(layers "F.Cu" "F.Mask" "F.Paste")
			(roundrect_rratio 0.25)
			(net 372 "Net-(U23-OE)")
			(pintype "passive")
		)
		(pad "2" smd roundrect
			(at 0.48 0 90)
			(size 0.59 0.64)
			(layers "F.Cu" "F.Mask" "F.Paste")
			(roundrect_rratio 0.25)
			(net 878 "/USB PHY/~{BDBUS3}")
			(pintype "passive")
		)
	)
	(footprint "antmicro-footprints:R_0402_1005Metric"
		(layer "F.Cu")
		(at 256.13 184.26 90)
		(descr "Resistor SMD 0402")
		(tags "resistor SMD 0402")
		(property "Reference" "R46"
			(at 0.76 0.42 90)
			(layer "F.SilkS")
			(effects
				(font
					(size 0.7 0.7)
					(thickness 0.15)
				)
				(justify left bottom)
			)
		)
		(property "Value" "R_47k_0402"
			(at 0 1.4 90)
			(layer "F.Fab")
			(effects
				(font
					(size 0.7 0.7)
					(thickness 0.15)
				)
				(justify left bottom)
			)
		)
		(property "Description" "SMD Chip Resistor, 47 kohm, ± 1%, 62.5 mW, 0402 [1005 Metric], Thick Film, General Purpose"
			(at 0 0 90)
			(layer "F.Fab")
			(hide yes)
			(effects
				(font
					(size 1.27 1.27)
					(thickness 0.15)
				)
			)
		)
		(property "Author" "Antmicro"
			(at 440.39 -71.87 0)
			(layer "F.Fab")
			(hide yes)
			(effects
				(font
					(size 1 1)
					(thickness 0.15)
				)
			)
		)
		(property "License" "Apache-2.0"
			(at 440.39 -71.87 0)
			(layer "F.Fab")
			(hide yes)
			(effects
				(font
					(size 1 1)
					(thickness 0.15)
				)
			)
		)
		(property "MPN" "CR0402-FX-4702GLF"
			(at 440.39 -71.87 0)
			(layer "F.Fab")
			(hide yes)
			(effects
				(font
					(size 1 1)
					(thickness 0.15)
				)
			)
		)
		(property "Manufacturer" "Bourns"
			(at 440.39 -71.87 0)
			(layer "F.Fab")
			(hide yes)
			(effects
				(font
					(size 1 1)
					(thickness 0.15)
				)
			)
		)
		(property "Tolerance" "1%"
			(at 440.39 -71.87 0)
			(layer "F.Fab")
			(hide yes)
			(effects
				(font
					(size 1 1)
					(thickness 0.15)
				)
			)
		)
		(property "Val" "47k"
			(at 440.39 -71.87 0)
			(layer "F.Fab")
			(hide yes)
			(effects
				(font
					(size 1 1)
					(thickness 0.15)
				)
			)
		)
		(sheetname "Power supply")
		(sheetfile "power-supply.kicad_sch")
		(attr smd)
		(fp_rect
			(start -0.925 -0.47)
			(end 0.925 0.47)
			(stroke
				(width 0.05)
				(type default)
			)
			(fill no)
			(layer "F.CrtYd")
		)
		(fp_rect
			(start -0.5 -0.25)
			(end 0.5 0.25)
			(stroke
				(width 0.15)
				(type solid)
			)
			(fill no)
			(layer "F.Fab")
		)
		(pad "1" smd roundrect
			(at -0.48 0 90)
			(size 0.59 0.64)
			(layers "F.Cu" "F.Mask" "F.Paste")
			(roundrect_rratio 0.25)
			(net 18 "Net-(D9-A)")
			(pintype "passive")
		)
		(pad "2" smd roundrect
			(at 0.48 0 90)
			(size 0.59 0.64)
			(layers "F.Cu" "F.Mask" "F.Paste")
			(roundrect_rratio 0.25)
			(net 698 "/Power supply/VDD")
			(pintype "passive")
		)
	)
)
